(kicad_pcb
	(version 20260206)
	(generator "pcbnew")
	(generator_version "10.0")
	(general
		(thickness 1.6)
		(legacy_teardrops no)
	)
	(paper "A4")
	(title_block
		(title "04192023_DAF0TMB3IC0_F0TG_MB_C_brd_V02_OCP.brd")
		(comment 1 "Grand Teton / footprint 2783 of 8354 (U26), pads 2894-3005 of 6102")
	)
	(layers
		(0 "F.Cu" signal "TOP")
		(4 "In1.Cu" signal "GND")
		(6 "In2.Cu" signal "IN1")
		(8 "In3.Cu" signal "GND1")
		(10 "In4.Cu" signal "IN2")
		(12 "In5.Cu" signal "GND2")
		(14 "In6.Cu" signal "IN3")
		(16 "In7.Cu" signal "GND3")
		(18 "In8.Cu" signal "VCC")
		(20 "In9.Cu" signal "VCC1")
		(22 "In10.Cu" signal "GND4")
		(24 "In11.Cu" signal "IN4")
		(26 "In12.Cu" signal "GND5")
		(28 "In13.Cu" signal "IN5")
		(30 "In14.Cu" signal "GND6")
		(32 "In15.Cu" signal "IN6")
		(34 "In16.Cu" signal "GND7")
		(2 "B.Cu" signal "BOTTOM")
		(9 "F.Adhes" user "F.Adhesive")
		(11 "B.Adhes" user "B.Adhesive")
		(13 "F.Paste" user "Package Geometry/Pastemask Top")
		(15 "B.Paste" user "Package Geometry/Pastemask Bottom")
		(5 "F.SilkS" user "Ref Des/Silkscreen Top")
		(7 "B.SilkS" user "Ref Des/Silkscreen Bottom")
		(1 "F.Mask" user "Board Geometry/Soldermask Top")
		(3 "B.Mask" user "Board Geometry/Soldermask Bottom")
		(17 "Dwgs.User" user "User.Drawings")
		(19 "Cmts.User" user "User.Comments")
		(21 "Eco1.User" user "User.Eco1")
		(23 "Eco2.User" user "User.Eco2")
		(25 "Edge.Cuts" user "Board Geometry/Outline")
		(27 "Margin" user)
		(31 "F.CrtYd" user "Package Geometry/Place Bound Top")
		(29 "B.CrtYd" user "Package Geometry/Place Bound Bottom")
		(35 "F.Fab" user "Ref Des/Assembly Top")
		(33 "B.Fab" user "Ref Des/Assembly Bottom")
	)
	(footprint ""
		(layer "F.Cu")
		(at 111.927894 -258.880356 180)
		(property "Reference" "U26"
			(at -45.05579 -61.794136 0)
			(unlocked yes)
			(layer "F.SilkS")
			(effects
				(font
					(size 0.7874 0.5842)
					(thickness 0.1524)
				)
			)
		)
		(property "Value" ""
			(at 0 0 180)
			(layer "F.Fab")
			(effects
				(font
					(size 1.27 1.27)
				)
			)
		)
		(duplicate_pad_numbers_are_jumpers no)
		(pad "CB15" smd circle
			(at -21.770086 14.940026 180)
			(size 0.450088 0.450088)
			(layers "F.Cu" "F.Mask" "F.Paste")
			(net "GND")
		)
		(pad "CB16" smd circle
			(at -20.830032 14.940026 180)
			(size 0.450088 0.450088)
			(layers "F.Cu" "F.Mask" "F.Paste")
			(net "M_J_CPU1_SB_DQ<0>")
		)
		(pad "CB17" smd circle
			(at -19.889978 14.940026 180)
			(size 0.450088 0.450088)
			(layers "F.Cu" "F.Mask" "F.Paste")
			(net "GND")
		)
		(pad "CB18" smd circle
			(at -18.949924 14.940026 180)
			(size 0.450088 0.450088)
			(layers "F.Cu" "F.Mask" "F.Paste")
			(net "M_J_CPU1_SB_CB<3>")
		)
		(pad "CB19" smd circle
			(at -18.010124 14.940026 180)
			(size 0.450088 0.450088)
			(layers "F.Cu" "F.Mask" "F.Paste")
			(net "GND")
		)
		(pad "CB20" smd circle
			(at -17.07007 14.940026 180)
			(size 0.450088 0.450088)
			(layers "F.Cu" "F.Mask" "F.Paste")
			(net "M_I_CPU1_SB_DQ<0>")
		)
		(pad "CB21" smd circle
			(at -16.130016 14.940026 180)
			(size 0.450088 0.450088)
			(layers "F.Cu" "F.Mask" "F.Paste")
			(net "M_I_CPU1_SB_CB<3>")
		)
		(pad "CB22" smd circle
			(at -15.189962 14.940026 180)
			(size 0.450088 0.450088)
			(layers "F.Cu" "F.Mask" "F.Paste")
			(net "PVDD11_S3_P1")
		)
		(pad "CB23" smd circle
			(at -14.249908 14.940026 180)
			(size 0.450088 0.450088)
			(layers "F.Cu" "F.Mask" "F.Paste")
			(net "GND")
		)
		(pad "CB24" smd circle
			(at -13.310108 14.940026 180)
			(size 0.450088 0.450088)
			(layers "F.Cu" "F.Mask" "F.Paste")
			(net "GND")
		)
		(pad "CB25" smd circle
			(at -12.370054 14.940026 180)
			(size 0.450088 0.450088)
			(layers "F.Cu" "F.Mask" "F.Paste")
			(net "GND")
		)
		(pad "CB26" smd circle
			(at -11.43 14.940026 180)
			(size 0.450088 0.450088)
			(layers "F.Cu" "F.Mask" "F.Paste")
			(net "GND")
		)
		(pad "CB27" smd circle
			(at -10.489946 14.940026 180)
			(size 0.450088 0.450088)
			(layers "F.Cu" "F.Mask" "F.Paste")
			(net "GND")
		)
		(pad "CB28" smd circle
			(at -9.549892 14.940026 180)
			(size 0.450088 0.450088)
			(layers "F.Cu" "F.Mask" "F.Paste")
			(net "GND")
		)
		(pad "CB29" smd circle
			(at -8.610092 14.940026 180)
			(size 0.450088 0.450088)
			(layers "F.Cu" "F.Mask" "F.Paste")
			(net "GND")
		)
		(pad "CB30" smd circle
			(at -7.670038 14.940026 180)
			(size 0.450088 0.450088)
			(layers "F.Cu" "F.Mask" "F.Paste")
			(net "GND")
		)
		(pad "CB31" smd circle
			(at -6.729984 14.940026 180)
			(size 0.450088 0.450088)
			(layers "F.Cu" "F.Mask" "F.Paste")
			(net "GND")
		)
		(pad "CB32" smd circle
			(at -5.78993 14.940026 180)
			(size 0.450088 0.450088)
			(layers "F.Cu" "F.Mask" "F.Paste")
			(net "GND")
		)
		(pad "CB33" smd circle
			(at -4.849876 14.940026 180)
			(size 0.450088 0.450088)
			(layers "F.Cu" "F.Mask" "F.Paste")
			(net "GND")
		)
		(pad "CB34" smd circle
			(at -3.910076 14.940026 180)
			(size 0.450088 0.450088)
			(layers "F.Cu" "F.Mask" "F.Paste")
			(net "GND")
		)
		(pad "CB35" smd circle
			(at -2.970022 14.940026 180)
			(size 0.450088 0.450088)
			(layers "F.Cu" "F.Mask" "F.Paste")
			(net "P5E_CPU1_P2_TX_DN<2>")
		)
		(pad "CB36" smd circle
			(at -2.029968 14.940026 180)
			(size 0.450088 0.450088)
			(layers "F.Cu" "F.Mask" "F.Paste")
			(net "P5E_CPU1_P2_TX_DP<2>")
		)
		(pad "CB37" smd circle
			(at -1.089914 14.940026 180)
			(size 0.450088 0.450088)
			(layers "F.Cu" "F.Mask" "F.Paste")
			(net "GND")
		)
		(pad "CB39" smd circle
			(at 0.78994 14.940026 180)
			(size 0.450088 0.450088)
			(layers "F.Cu" "F.Mask" "F.Paste")
			(net "GND")
		)
		(pad "CB40" smd circle
			(at 1.729994 14.940026 180)
			(size 0.450088 0.450088)
			(layers "F.Cu" "F.Mask" "F.Paste")
			(net "P5E_CPU1_P0_RX_DP<13>")
		)
		(pad "CB41" smd circle
			(at 2.670048 14.940026 180)
			(size 0.450088 0.450088)
			(layers "F.Cu" "F.Mask" "F.Paste")
			(net "P5E_CPU1_P0_RX_DN<13>")
		)
		(pad "CB42" smd circle
			(at 3.610102 14.940026 180)
			(size 0.450088 0.450088)
			(layers "F.Cu" "F.Mask" "F.Paste")
			(net "GND")
		)
		(pad "CB43" smd circle
			(at 4.549902 14.940026 180)
			(size 0.450088 0.450088)
			(layers "F.Cu" "F.Mask" "F.Paste")
			(net "GND")
		)
		(pad "CB44" smd circle
			(at 5.489956 14.940026 180)
			(size 0.450088 0.450088)
			(layers "F.Cu" "F.Mask" "F.Paste")
			(net "GND")
		)
		(pad "CB45" smd circle
			(at 6.43001 14.940026 180)
			(size 0.450088 0.450088)
			(layers "F.Cu" "F.Mask" "F.Paste")
			(net "GND")
		)
		(pad "CB46" smd circle
			(at 7.370064 14.940026 180)
			(size 0.450088 0.450088)
			(layers "F.Cu" "F.Mask" "F.Paste")
			(net "GND")
		)
		(pad "CB47" smd circle
			(at 8.310118 14.940026 180)
			(size 0.450088 0.450088)
			(layers "F.Cu" "F.Mask" "F.Paste")
			(net "GND")
		)
		(pad "CB48" smd circle
			(at 9.249918 14.940026 180)
			(size 0.450088 0.450088)
			(layers "F.Cu" "F.Mask" "F.Paste")
			(net "GND")
		)
		(pad "CB49" smd circle
			(at 10.189972 14.940026 180)
			(size 0.450088 0.450088)
			(layers "F.Cu" "F.Mask" "F.Paste")
			(net "GND")
		)
		(pad "CB50" smd circle
			(at 11.130026 14.940026 180)
			(size 0.450088 0.450088)
			(layers "F.Cu" "F.Mask" "F.Paste")
			(net "GND")
		)
		(pad "CB51" smd circle
			(at 12.07008 14.940026 180)
			(size 0.450088 0.450088)
			(layers "F.Cu" "F.Mask" "F.Paste")
			(net "GND")
		)
		(pad "CB52" smd circle
			(at 13.00988 14.940026 180)
			(size 0.450088 0.450088)
			(layers "F.Cu" "F.Mask" "F.Paste")
			(net "GND")
		)
		(pad "CB53" smd circle
			(at 13.949934 14.940026 180)
			(size 0.450088 0.450088)
			(layers "F.Cu" "F.Mask" "F.Paste")
			(net "GND")
		)
		(pad "CB54" smd circle
			(at 14.889988 14.940026 180)
			(size 0.450088 0.450088)
			(layers "F.Cu" "F.Mask" "F.Paste")
			(net "PVDDIO_P1")
		)
		(pad "CB55" smd circle
			(at 15.830042 14.940026 180)
			(size 0.450088 0.450088)
			(layers "F.Cu" "F.Mask" "F.Paste")
			(net "M_C_CPU1_SB_CB<3>")
		)
		(pad "CB56" smd circle
			(at 16.770096 14.940026 180)
			(size 0.450088 0.450088)
			(layers "F.Cu" "F.Mask" "F.Paste")
			(net "M_C_CPU1_SB_DQ<0>")
		)
		(pad "CB57" smd circle
			(at 17.709896 14.940026 180)
			(size 0.450088 0.450088)
			(layers "F.Cu" "F.Mask" "F.Paste")
			(net "GND")
		)
		(pad "CB58" smd circle
			(at 18.64995 14.940026 180)
			(size 0.450088 0.450088)
			(layers "F.Cu" "F.Mask" "F.Paste")
			(net "M_D_CPU1_SB_CB<3>")
		)
		(pad "CB59" smd circle
			(at 19.590004 14.940026 180)
			(size 0.450088 0.450088)
			(layers "F.Cu" "F.Mask" "F.Paste")
			(net "GND")
		)
		(pad "CB60" smd circle
			(at 20.530058 14.940026 180)
			(size 0.450088 0.450088)
			(layers "F.Cu" "F.Mask" "F.Paste")
			(net "M_D_CPU1_SB_DQ<0>")
		)
		(pad "CB61" smd circle
			(at 21.470112 14.940026 180)
			(size 0.450088 0.450088)
			(layers "F.Cu" "F.Mask" "F.Paste")
			(net "GND")
		)
		(pad "CB62" smd circle
			(at 22.409912 14.940026 180)
			(size 0.450088 0.450088)
			(layers "F.Cu" "F.Mask" "F.Paste")
			(net "M_B_CPU1_SB_CB<3>")
		)
		(pad "CB63" smd circle
			(at 23.349966 14.940026 180)
			(size 0.450088 0.450088)
			(layers "F.Cu" "F.Mask" "F.Paste")
			(net "M_B_CPU1_SB_DQ<0>")
		)
		(pad "CB64" smd circle
			(at 24.29002 14.940026 180)
			(size 0.450088 0.450088)
			(layers "F.Cu" "F.Mask" "F.Paste")
			(net "GND")
		)
		(pad "CB65" smd circle
			(at 25.230074 14.940026 180)
			(size 0.450088 0.450088)
			(layers "F.Cu" "F.Mask" "F.Paste")
			(net "M_F_CPU1_SB_CB<3>")
		)
		(pad "CB66" smd circle
			(at 26.170128 14.940026 180)
			(size 0.450088 0.450088)
			(layers "F.Cu" "F.Mask" "F.Paste")
			(net "GND")
		)
		(pad "CB67" smd circle
			(at 27.109928 14.940026 180)
			(size 0.450088 0.450088)
			(layers "F.Cu" "F.Mask" "F.Paste")
			(net "M_F_CPU1_SB_DQ<0>")
		)
		(pad "CB68" smd circle
			(at 28.049982 14.940026 180)
			(size 0.450088 0.450088)
			(layers "F.Cu" "F.Mask" "F.Paste")
			(net "GND")
		)
		(pad "CB69" smd circle
			(at 28.990036 14.940026 180)
			(size 0.450088 0.450088)
			(layers "F.Cu" "F.Mask" "F.Paste")
			(net "M_E_CPU1_SB_CB<3>")
		)
		(pad "CB70" smd circle
			(at 29.93009 14.940026 180)
			(size 0.450088 0.450088)
			(layers "F.Cu" "F.Mask" "F.Paste")
			(net "M_E_CPU1_SB_DQ<0>")
		)
		(pad "CB71" smd circle
			(at 30.86989 14.940026 180)
			(size 0.450088 0.450088)
			(layers "F.Cu" "F.Mask" "F.Paste")
			(net "GND")
		)
		(pad "CB72" smd circle
			(at 31.809944 14.940026 180)
			(size 0.450088 0.450088)
			(layers "F.Cu" "F.Mask" "F.Paste")
			(net "M_A_CPU1_SB_CB<3>")
		)
		(pad "CB73" smd circle
			(at 32.749998 14.940026 180)
			(size 0.450088 0.450088)
			(layers "F.Cu" "F.Mask" "F.Paste")
			(net "GND")
		)
		(pad "CB74" smd circle
			(at 33.690052 14.940026 180)
			(size 0.450088 0.450088)
			(layers "F.Cu" "F.Mask" "F.Paste")
			(net "M_A_CPU1_SB_DQ<0>")
		)
		(pad "CC1" smd circle
			(at -34.459926 15.750032 180)
			(size 0.450088 0.450088)
			(layers "F.Cu" "F.Mask" "F.Paste")
			(net "GND")
		)
		(pad "CC2" smd circle
			(at -33.519872 15.750032 180)
			(size 0.450088 0.450088)
			(layers "F.Cu" "F.Mask" "F.Paste")
			(net "M_G_CPU1_SB_DQ<2>")
		)
		(pad "CC3" smd circle
			(at -32.580072 15.750032 180)
			(size 0.450088 0.450088)
			(layers "F.Cu" "F.Mask" "F.Paste")
			(net "M_G_CPU1_SB_DQ<1>")
		)
		(pad "CC4" smd circle
			(at -31.640018 15.750032 180)
			(size 0.450088 0.450088)
			(layers "F.Cu" "F.Mask" "F.Paste")
			(net "GND")
		)
		(pad "CC5" smd circle
			(at -30.699964 15.750032 180)
			(size 0.450088 0.450088)
			(layers "F.Cu" "F.Mask" "F.Paste")
			(net "M_K_CPU1_SB_DQ<2>")
		)
		(pad "CC6" smd circle
			(at -29.75991 15.750032 180)
			(size 0.450088 0.450088)
			(layers "F.Cu" "F.Mask" "F.Paste")
			(net "GND")
		)
		(pad "CC7" smd circle
			(at -28.82011 15.750032 180)
			(size 0.450088 0.450088)
			(layers "F.Cu" "F.Mask" "F.Paste")
			(net "M_K_CPU1_SB_DQ<1>")
		)
		(pad "CC8" smd circle
			(at -27.880056 15.750032 180)
			(size 0.450088 0.450088)
			(layers "F.Cu" "F.Mask" "F.Paste")
			(net "GND")
		)
		(pad "CC9" smd circle
			(at -26.940002 15.750032 180)
			(size 0.450088 0.450088)
			(layers "F.Cu" "F.Mask" "F.Paste")
			(net "M_L_CPU1_SB_DQ<2>")
		)
		(pad "CC10" smd circle
			(at -25.999948 15.750032 180)
			(size 0.450088 0.450088)
			(layers "F.Cu" "F.Mask" "F.Paste")
			(net "M_L_CPU1_SB_DQ<1>")
		)
		(pad "CC11" smd circle
			(at -25.059894 15.750032 180)
			(size 0.450088 0.450088)
			(layers "F.Cu" "F.Mask" "F.Paste")
			(net "GND")
		)
		(pad "CC12" smd circle
			(at -24.120094 15.750032 180)
			(size 0.450088 0.450088)
			(layers "F.Cu" "F.Mask" "F.Paste")
			(net "M_H_CPU1_SB_DQ<2>")
		)
		(pad "CC13" smd circle
			(at -23.18004 15.750032 180)
			(size 0.450088 0.450088)
			(layers "F.Cu" "F.Mask" "F.Paste")
			(net "GND")
		)
		(pad "CC14" smd circle
			(at -22.239986 15.750032 180)
			(size 0.450088 0.450088)
			(layers "F.Cu" "F.Mask" "F.Paste")
			(net "M_H_CPU1_SB_DQ<1>")
		)
		(pad "CC15" smd circle
			(at -21.299932 15.750032 180)
			(size 0.450088 0.450088)
			(layers "F.Cu" "F.Mask" "F.Paste")
			(net "GND")
		)
		(pad "CC16" smd circle
			(at -20.359878 15.750032 180)
			(size 0.450088 0.450088)
			(layers "F.Cu" "F.Mask" "F.Paste")
			(net "M_J_CPU1_SB_DQ<2>")
		)
		(pad "CC17" smd circle
			(at -19.420078 15.750032 180)
			(size 0.450088 0.450088)
			(layers "F.Cu" "F.Mask" "F.Paste")
			(net "M_J_CPU1_SB_DQ<1>")
		)
		(pad "CC18" smd circle
			(at -18.480024 15.750032 180)
			(size 0.450088 0.450088)
			(layers "F.Cu" "F.Mask" "F.Paste")
			(net "GND")
		)
		(pad "CC19" smd circle
			(at -17.53997 15.750032 180)
			(size 0.450088 0.450088)
			(layers "F.Cu" "F.Mask" "F.Paste")
			(net "M_I_CPU1_SB_DQ<2>")
		)
		(pad "CC20" smd circle
			(at -16.599916 15.750032 180)
			(size 0.450088 0.450088)
			(layers "F.Cu" "F.Mask" "F.Paste")
			(net "GND")
		)
		(pad "CC21" smd circle
			(at -15.660116 15.750032 180)
			(size 0.450088 0.450088)
			(layers "F.Cu" "F.Mask" "F.Paste")
			(net "M_I_CPU1_SB_DQ<1>")
		)
		(pad "CC22" smd circle
			(at -14.720062 15.750032 180)
			(size 0.450088 0.450088)
			(layers "F.Cu" "F.Mask" "F.Paste")
			(net "GND")
		)
		(pad "CC23" smd circle
			(at -13.780008 15.750032 180)
			(size 0.450088 0.450088)
			(layers "F.Cu" "F.Mask" "F.Paste")
			(net "P5E_CPU1_P3_TX_DN<13>")
		)
		(pad "CC24" smd circle
			(at -12.839954 15.750032 180)
			(size 0.450088 0.450088)
			(layers "F.Cu" "F.Mask" "F.Paste")
			(net "P5E_CPU1_P3_TX_DP<13>")
		)
		(pad "CC25" smd circle
			(at -11.8999 15.750032 180)
			(size 0.450088 0.450088)
			(layers "F.Cu" "F.Mask" "F.Paste")
			(net "GND")
		)
		(pad "CC26" smd circle
			(at -10.9601 15.750032 180)
			(size 0.450088 0.450088)
			(layers "F.Cu" "F.Mask" "F.Paste")
			(net "P5E_CPU1_P3_TX_DN<10>")
		)
		(pad "CC27" smd circle
			(at -10.020046 15.750032 180)
			(size 0.450088 0.450088)
			(layers "F.Cu" "F.Mask" "F.Paste")
			(net "P5E_CPU1_P3_TX_DP<10>")
		)
		(pad "CC28" smd circle
			(at -9.079992 15.750032 180)
			(size 0.450088 0.450088)
			(layers "F.Cu" "F.Mask" "F.Paste")
			(net "GND")
		)
		(pad "CC29" smd circle
			(at -8.139938 15.750032 180)
			(size 0.450088 0.450088)
			(layers "F.Cu" "F.Mask" "F.Paste")
			(net "P5E_CPU1_P3_TX_DN<7>")
		)
		(pad "CC30" smd circle
			(at -7.199884 15.750032 180)
			(size 0.450088 0.450088)
			(layers "F.Cu" "F.Mask" "F.Paste")
			(net "P5E_CPU1_P3_TX_DP<7>")
		)
		(pad "CC31" smd circle
			(at -6.260084 15.750032 180)
			(size 0.450088 0.450088)
			(layers "F.Cu" "F.Mask" "F.Paste")
			(net "GND")
		)
		(pad "CC32" smd circle
			(at -5.32003 15.750032 180)
			(size 0.450088 0.450088)
			(layers "F.Cu" "F.Mask" "F.Paste")
			(net "P5E_CPU1_P3_TX_DN<3>")
		)
		(pad "CC33" smd circle
			(at -4.379976 15.750032 180)
			(size 0.450088 0.450088)
			(layers "F.Cu" "F.Mask" "F.Paste")
			(net "P5E_CPU1_P3_TX_DP<3>")
		)
		(pad "CC34" smd circle
			(at -3.439922 15.750032 180)
			(size 0.450088 0.450088)
			(layers "F.Cu" "F.Mask" "F.Paste")
			(net "GND")
		)
		(pad "CC35" smd circle
			(at -2.500122 15.750032 180)
			(size 0.450088 0.450088)
			(layers "F.Cu" "F.Mask" "F.Paste")
			(net "PVDDCR_CPU1_P1")
		)
		(pad "CC36" smd circle
			(at -1.560068 15.750032 180)
			(size 0.450088 0.450088)
			(layers "F.Cu" "F.Mask" "F.Paste")
			(net "PVDDCR_CPU1_P1")
		)
		(pad "CC40" smd circle
			(at 1.260094 15.750032 180)
			(size 0.450088 0.450088)
			(layers "F.Cu" "F.Mask" "F.Paste")
			(net "PVDDCR_CPU1_P1")
		)
		(pad "CC41" smd circle
			(at 2.199894 15.750032 180)
			(size 0.450088 0.450088)
			(layers "F.Cu" "F.Mask" "F.Paste")
			(net "PVDDCR_CPU1_P1")
		)
		(pad "CC42" smd circle
			(at 3.139948 15.750032 180)
			(size 0.450088 0.450088)
			(layers "F.Cu" "F.Mask" "F.Paste")
			(net "GND")
		)
		(pad "CC43" smd circle
			(at 4.080002 15.750032 180)
			(size 0.450088 0.450088)
			(layers "F.Cu" "F.Mask" "F.Paste")
			(net "P5E_CPU1_P1_RX_DP<12>")
		)
		(pad "CC44" smd circle
			(at 5.020056 15.750032 180)
			(size 0.450088 0.450088)
			(layers "F.Cu" "F.Mask" "F.Paste")
			(net "P5E_CPU1_P1_RX_DN<12>")
		)
		(pad "CC45" smd circle
			(at 5.96011 15.750032 180)
			(size 0.450088 0.450088)
			(layers "F.Cu" "F.Mask" "F.Paste")
			(net "GND")
		)
		(pad "CC46" smd circle
			(at 6.89991 15.750032 180)
			(size 0.450088 0.450088)
			(layers "F.Cu" "F.Mask" "F.Paste")
			(net "P5E_CPU1_P1_RX_DP<8>")
		)
		(pad "CC47" smd circle
			(at 7.839964 15.750032 180)
			(size 0.450088 0.450088)
			(layers "F.Cu" "F.Mask" "F.Paste")
			(net "P5E_CPU1_P1_RX_DN<8>")
		)
		(pad "CC48" smd circle
			(at 8.780018 15.750032 180)
			(size 0.450088 0.450088)
			(layers "F.Cu" "F.Mask" "F.Paste")
			(net "GND")
		)
		(pad "CC49" smd circle
			(at 9.720072 15.750032 180)
			(size 0.450088 0.450088)
			(layers "F.Cu" "F.Mask" "F.Paste")
			(net "P5E_CPU1_P1_RX_DP<5>")
		)
		(pad "CC50" smd circle
			(at 10.659872 15.750032 180)
			(size 0.450088 0.450088)
			(layers "F.Cu" "F.Mask" "F.Paste")
			(net "P5E_CPU1_P1_RX_DN<5>")
		)
		(pad "CC51" smd circle
			(at 11.599926 15.750032 180)
			(size 0.450088 0.450088)
			(layers "F.Cu" "F.Mask" "F.Paste")
			(net "GND")
		)
		(pad "CC52" smd circle
			(at 12.53998 15.750032 180)
			(size 0.450088 0.450088)
			(layers "F.Cu" "F.Mask" "F.Paste")
			(net "P5E_CPU1_P1_RX_DP<2>")
		)
		(pad "CC53" smd circle
			(at 13.480034 15.750032 180)
			(size 0.450088 0.450088)
			(layers "F.Cu" "F.Mask" "F.Paste")
			(net "P5E_CPU1_P1_RX_DN<2>")
		)
		(pad "CC54" smd circle
			(at 14.420088 15.750032 180)
			(size 0.450088 0.450088)
			(layers "F.Cu" "F.Mask" "F.Paste")
			(net "GND")
		)
		(pad "CC55" smd circle
			(at 15.359888 15.750032 180)
			(size 0.450088 0.450088)
			(layers "F.Cu" "F.Mask" "F.Paste")
			(net "M_C_CPU1_SB_DQ<1>")
		)
		(pad "CC56" smd circle
			(at 16.299942 15.750032 180)
			(size 0.450088 0.450088)
			(layers "F.Cu" "F.Mask" "F.Paste")
			(net "GND")
		)
	)
)
